(kicad_pcb
	(version 20260206)
	(generator "pcbnew")
	(generator_version "10.0")
	(general
		(thickness 1.6)
		(legacy_teardrops no)
	)
	(paper "A4")
	(title_block
		(title "04192023_DAF0TMB3IC0_F0TG_MB_C_brd_V02_OCP.brd")
		(comment 1 "Grand Teton / footprints 8217-8224 of 8354")
	)
	(layers
		(0 "F.Cu" signal "TOP")
		(4 "In1.Cu" signal "GND")
		(6 "In2.Cu" signal "IN1")
		(8 "In3.Cu" signal "GND1")
		(10 "In4.Cu" signal "IN2")
		(12 "In5.Cu" signal "GND2")
		(14 "In6.Cu" signal "IN3")
		(16 "In7.Cu" signal "GND3")
		(18 "In8.Cu" signal "VCC")
		(20 "In9.Cu" signal "VCC1")
		(22 "In10.Cu" signal "GND4")
		(24 "In11.Cu" signal "IN4")
		(26 "In12.Cu" signal "GND5")
		(28 "In13.Cu" signal "IN5")
		(30 "In14.Cu" signal "GND6")
		(32 "In15.Cu" signal "IN6")
		(34 "In16.Cu" signal "GND7")
		(2 "B.Cu" signal "BOTTOM")
		(9 "F.Adhes" user "F.Adhesive")
		(11 "B.Adhes" user "B.Adhesive")
		(13 "F.Paste" user "Package Geometry/Pastemask Top")
		(15 "B.Paste" user "Package Geometry/Pastemask Bottom")
		(5 "F.SilkS" user "Ref Des/Silkscreen Top")
		(7 "B.SilkS" user "Ref Des/Silkscreen Bottom")
		(1 "F.Mask" user "Board Geometry/Soldermask Top")
		(3 "B.Mask" user "Board Geometry/Soldermask Bottom")
		(17 "Dwgs.User" user "User.Drawings")
		(19 "Cmts.User" user "User.Comments")
		(21 "Eco1.User" user "User.Eco1")
		(23 "Eco2.User" user "User.Eco2")
		(25 "Edge.Cuts" user "Board Geometry/Outline")
		(27 "Margin" user)
		(31 "F.CrtYd" user "Package Geometry/Place Bound Top")
		(29 "B.CrtYd" user "Package Geometry/Place Bound Bottom")
		(35 "F.Fab" user "Ref Des/Assembly Top")
		(33 "B.Fab" user "Ref Des/Assembly Bottom")
	)
	(footprint ""
		(layer "B.Cu")
		(at 105.605834 -272.284952)
		(property "Reference" "C2395"
			(at 0 0 0)
			(layer "B.SilkS")
			(hide yes)
			(effects
				(font
					(size 1.27 1.27)
				)
				(justify mirror)
			)
		)
		(property "Value" ""
			(at 0 0 0)
			(layer "B.Fab")
			(effects
				(font
					(size 1.27 1.27)
				)
				(justify mirror)
			)
		)
		(duplicate_pad_numbers_are_jumpers no)
		(fp_line
			(start -0.7874 -0.4064)
			(end -0.7874 0.4064)
			(stroke
				(width 0.1524)
				(type default)
			)
			(layer "B.SilkS")
		)
		(fp_line
			(start -0.7874 0.4064)
			(end 0.7874 0.4064)
			(stroke
				(width 0.1524)
				(type default)
			)
			(layer "B.SilkS")
		)
		(fp_line
			(start 0.7874 -0.4064)
			(end -0.7874 -0.4064)
			(stroke
				(width 0.1524)
				(type default)
			)
			(layer "B.SilkS")
		)
		(fp_line
			(start 0.7874 0.4064)
			(end 0.7874 -0.4064)
			(stroke
				(width 0.1524)
				(type default)
			)
			(layer "B.SilkS")
		)
		(fp_line
			(start -0.67945 -0.3048)
			(end -0.67945 0.3048)
			(stroke
				(width 0.1)
				(type default)
			)
			(layer "B.Fab")
		)
		(fp_line
			(start -0.67945 0.3048)
			(end -0.120396 0.3048)
			(stroke
				(width 0.1)
				(type default)
			)
			(layer "B.Fab")
		)
		(fp_line
			(start -0.12065 -0.3048)
			(end -0.67945 -0.3048)
			(stroke
				(width 0.1)
				(type default)
			)
			(layer "B.Fab")
		)
		(fp_line
			(start -0.12065 -0.2794)
			(end -0.12065 -0.3048)
			(stroke
				(width 0.1)
				(type default)
			)
			(layer "B.Fab")
		)
		(fp_line
			(start -0.120396 0.2794)
			(end 0.12065 0.2794)
			(stroke
				(width 0.1)
				(type default)
			)
			(layer "B.Fab")
		)
		(fp_line
			(start -0.120396 0.3048)
			(end -0.120396 0.2794)
			(stroke
				(width 0.1)
				(type default)
			)
			(layer "B.Fab")
		)
		(fp_line
			(start 0.12065 -0.305054)
			(end 0.12065 -0.2794)
			(stroke
				(width 0.1)
				(type default)
			)
			(layer "B.Fab")
		)
		(fp_line
			(start 0.12065 -0.2794)
			(end -0.12065 -0.2794)
			(stroke
				(width 0.1)
				(type default)
			)
			(layer "B.Fab")
		)
		(fp_line
			(start 0.12065 0.2794)
			(end 0.12065 0.3048)
			(stroke
				(width 0.1)
				(type default)
			)
			(layer "B.Fab")
		)
		(fp_line
			(start 0.12065 0.3048)
			(end 0.67945 0.3048)
			(stroke
				(width 0.1)
				(type default)
			)
			(layer "B.Fab")
		)
		(fp_line
			(start 0.67945 -0.305054)
			(end 0.12065 -0.305054)
			(stroke
				(width 0.1)
				(type default)
			)
			(layer "B.Fab")
		)
		(fp_line
			(start 0.67945 0.3048)
			(end 0.67945 -0.305054)
			(stroke
				(width 0.1)
				(type default)
			)
			(layer "B.Fab")
		)
		(pad "1" smd circle
			(at 0.40005 0 180)
			(size 0 0)
			(layers "B.Cu" "B.Mask" "B.Paste")
			(net "PVDDCR_CPU1_P1")
		)
		(pad "2" smd circle
			(at -0.40005 0 180)
			(size 0 0)
			(layers "B.Cu" "B.Mask" "B.Paste")
			(net "GND")
		)
	)
	(footprint ""
		(layer "B.Cu")
		(at 405.22017 -202.891136 -90)
		(property "Reference" "R654"
			(at 0 0 90)
			(layer "B.SilkS")
			(hide yes)
			(effects
				(font
					(size 1.27 1.27)
				)
				(justify mirror)
			)
		)
		(property "Value" ""
			(at 0 0 90)
			(layer "B.Fab")
			(effects
				(font
					(size 1.27 1.27)
				)
				(justify mirror)
			)
		)
		(duplicate_pad_numbers_are_jumpers no)
		(fp_line
			(start -0.7874 0.4064)
			(end 0.7874 0.4064)
			(stroke
				(width 0.1524)
				(type default)
			)
			(layer "B.SilkS")
		)
		(fp_line
			(start 0.7874 0.4064)
			(end 0.7874 -0.4064)
			(stroke
				(width 0.1524)
				(type default)
			)
			(layer "B.SilkS")
		)
		(fp_line
			(start -0.7874 -0.4064)
			(end -0.7874 0.4064)
			(stroke
				(width 0.1524)
				(type default)
			)
			(layer "B.SilkS")
		)
		(fp_line
			(start 0.7874 -0.4064)
			(end -0.7874 -0.4064)
			(stroke
				(width 0.1524)
				(type default)
			)
			(layer "B.SilkS")
		)
		(fp_line
			(start -0.67945 0.3048)
			(end -0.120396 0.3048)
			(stroke
				(width 0.1)
				(type default)
			)
			(layer "B.Fab")
		)
		(fp_line
			(start -0.120396 0.3048)
			(end -0.120396 0.2794)
			(stroke
				(width 0.1)
				(type default)
			)
			(layer "B.Fab")
		)
		(fp_line
			(start 0.12065 0.3048)
			(end 0.67945 0.3048)
			(stroke
				(width 0.1)
				(type default)
			)
			(layer "B.Fab")
		)
		(fp_line
			(start 0.67945 0.3048)
			(end 0.67945 -0.305054)
			(stroke
				(width 0.1)
				(type default)
			)
			(layer "B.Fab")
		)
		(fp_line
			(start -0.120396 0.2794)
			(end 0.12065 0.2794)
			(stroke
				(width 0.1)
				(type default)
			)
			(layer "B.Fab")
		)
		(fp_line
			(start 0.12065 0.2794)
			(end 0.12065 0.3048)
			(stroke
				(width 0.1)
				(type default)
			)
			(layer "B.Fab")
		)
		(fp_line
			(start -0.12065 -0.2794)
			(end -0.12065 -0.3048)
			(stroke
				(width 0.1)
				(type default)
			)
			(layer "B.Fab")
		)
		(fp_line
			(start 0.12065 -0.2794)
			(end -0.12065 -0.2794)
			(stroke
				(width 0.1)
				(type default)
			)
			(layer "B.Fab")
		)
		(fp_line
			(start -0.67945 -0.3048)
			(end -0.67945 0.3048)
			(stroke
				(width 0.1)
				(type default)
			)
			(layer "B.Fab")
		)
		(fp_line
			(start -0.12065 -0.3048)
			(end -0.67945 -0.3048)
			(stroke
				(width 0.1)
				(type default)
			)
			(layer "B.Fab")
		)
		(fp_line
			(start 0.12065 -0.305054)
			(end 0.12065 -0.2794)
			(stroke
				(width 0.1)
				(type default)
			)
			(layer "B.Fab")
		)
		(fp_line
			(start 0.67945 -0.305054)
			(end 0.12065 -0.305054)
			(stroke
				(width 0.1)
				(type default)
			)
			(layer "B.Fab")
		)
		(pad "1" smd circle
			(at 0.40005 0 90)
			(size 0 0)
			(layers "B.Cu" "B.Mask" "B.Paste")
			(net "SCM_USB_OC_N")
		)
		(pad "2" smd circle
			(at -0.40005 0 90)
			(size 0 0)
			(layers "B.Cu" "B.Mask" "B.Paste")
			(net "P1V8_AUX")
		)
	)
	(footprint ""
		(layer "B.Cu")
		(at 103.951786 -104.674924 180)
		(property "Reference" ""
			(at 0 0 0)
			(layer "B.SilkS")
			(hide yes)
			(effects
				(font
					(size 1.27 1.27)
				)
				(justify mirror)
			)
		)
		(property "Value" ""
			(at 0 0 0)
			(layer "B.Fab")
			(effects
				(font
					(size 1.27 1.27)
				)
				(justify mirror)
			)
		)
		(duplicate_pad_numbers_are_jumpers no)
		(pad "1" smd circle
			(at 0 0)
			(size 0.9906 0.9906)
			(layers "B.Cu" "B.Mask" "B.Paste")
			(net "Net_45")
		)
		(zone
			(layer "B.Cu")
			(hatch none 0.5)
			(connect_pads
				(clearance 0)
			)
			(min_thickness 0.25)
			(keepout
				(tracks not_allowed)
				(vias allowed)
				(pads allowed)
				(copperpour not_allowed)
				(footprints allowed)
			)
			(placement
				(enabled no)
				(sheetname "")
			)
			(fill
				(thermal_gap 0.5)
				(thermal_bridge_width 0.5)
				(island_removal_mode 0)
			)
			(polygon
				(pts
					(arc
						(start 105.577386 -104.674924)
						(mid 102.326186 -104.674924)
						(end 105.577386 -104.674924)
					)
				)
			)
		)
	)
	(footprint ""
		(layer "B.Cu")
		(at 112.054386 -263.846564)
		(property "Reference" "C3904"
			(at 0 0 0)
			(layer "B.SilkS")
			(hide yes)
			(effects
				(font
					(size 1.27 1.27)
				)
				(justify mirror)
			)
		)
		(property "Value" ""
			(at 0 0 0)
			(layer "B.Fab")
			(effects
				(font
					(size 1.27 1.27)
				)
				(justify mirror)
			)
		)
		(duplicate_pad_numbers_are_jumpers no)
		(fp_line
			(start -0.7874 -0.4064)
			(end -0.7874 0.4064)
			(stroke
				(width 0.1524)
				(type default)
			)
			(layer "B.SilkS")
		)
		(fp_line
			(start -0.7874 0.4064)
			(end 0.7874 0.4064)
			(stroke
				(width 0.1524)
				(type default)
			)
			(layer "B.SilkS")
		)
		(fp_line
			(start 0.7874 -0.4064)
			(end -0.7874 -0.4064)
			(stroke
				(width 0.1524)
				(type default)
			)
			(layer "B.SilkS")
		)
		(fp_line
			(start 0.7874 0.4064)
			(end 0.7874 -0.4064)
			(stroke
				(width 0.1524)
				(type default)
			)
			(layer "B.SilkS")
		)
		(fp_line
			(start -0.67945 -0.3048)
			(end -0.67945 0.3048)
			(stroke
				(width 0.1)
				(type default)
			)
			(layer "B.Fab")
		)
		(fp_line
			(start -0.67945 0.3048)
			(end -0.120396 0.3048)
			(stroke
				(width 0.1)
				(type default)
			)
			(layer "B.Fab")
		)
		(fp_line
			(start -0.12065 -0.3048)
			(end -0.67945 -0.3048)
			(stroke
				(width 0.1)
				(type default)
			)
			(layer "B.Fab")
		)
		(fp_line
			(start -0.12065 -0.2794)
			(end -0.12065 -0.3048)
			(stroke
				(width 0.1)
				(type default)
			)
			(layer "B.Fab")
		)
		(fp_line
			(start -0.120396 0.2794)
			(end 0.12065 0.2794)
			(stroke
				(width 0.1)
				(type default)
			)
			(layer "B.Fab")
		)
		(fp_line
			(start -0.120396 0.3048)
			(end -0.120396 0.2794)
			(stroke
				(width 0.1)
				(type default)
			)
			(layer "B.Fab")
		)
		(fp_line
			(start 0.12065 -0.305054)
			(end 0.12065 -0.2794)
			(stroke
				(width 0.1)
				(type default)
			)
			(layer "B.Fab")
		)
		(fp_line
			(start 0.12065 -0.2794)
			(end -0.12065 -0.2794)
			(stroke
				(width 0.1)
				(type default)
			)
			(layer "B.Fab")
		)
		(fp_line
			(start 0.12065 0.2794)
			(end 0.12065 0.3048)
			(stroke
				(width 0.1)
				(type default)
			)
			(layer "B.Fab")
		)
		(fp_line
			(start 0.12065 0.3048)
			(end 0.67945 0.3048)
			(stroke
				(width 0.1)
				(type default)
			)
			(layer "B.Fab")
		)
		(fp_line
			(start 0.67945 -0.305054)
			(end 0.12065 -0.305054)
			(stroke
				(width 0.1)
				(type default)
			)
			(layer "B.Fab")
		)
		(fp_line
			(start 0.67945 0.3048)
			(end 0.67945 -0.305054)
			(stroke
				(width 0.1)
				(type default)
			)
			(layer "B.Fab")
		)
		(pad "1" smd circle
			(at 0.40005 0 180)
			(size 0 0)
			(layers "B.Cu" "B.Mask" "B.Paste")
			(net "PVDD11_S3_P1")
		)
		(pad "2" smd circle
			(at -0.40005 0 180)
			(size 0 0)
			(layers "B.Cu" "B.Mask" "B.Paste")
			(net "GND")
		)
	)
	(footprint ""
		(layer "B.Cu")
		(at 338.44611 -396.393162 -90)
		(property "Reference" "C635"
			(at 0 0 90)
			(layer "B.SilkS")
			(hide yes)
			(effects
				(font
					(size 1.27 1.27)
				)
				(justify mirror)
			)
		)
		(property "Value" ""
			(at 0 0 90)
			(layer "B.Fab")
			(effects
				(font
					(size 1.27 1.27)
				)
				(justify mirror)
			)
		)
		(duplicate_pad_numbers_are_jumpers no)
		(fp_line
			(start -0.299974 0.150114)
			(end 0.299974 0.150114)
			(stroke
				(width 0.1)
				(type default)
			)
			(layer "B.Fab")
		)
		(fp_line
			(start 0.299974 0.150114)
			(end 0.299974 -0.150114)
			(stroke
				(width 0.1)
				(type default)
			)
			(layer "B.Fab")
		)
		(fp_line
			(start -0.299974 -0.150114)
			(end -0.299974 0.150114)
			(stroke
				(width 0.1)
				(type default)
			)
			(layer "B.Fab")
		)
		(fp_line
			(start 0.299974 -0.150114)
			(end -0.299974 -0.150114)
			(stroke
				(width 0.1)
				(type default)
			)
			(layer "B.Fab")
		)
		(pad "1" smd rect
			(at 0.2667 0 90)
			(size 0.3048 0.381)
			(layers "B.Cu" "B.Mask" "B.Paste")
			(net "P0V9_CPU0_RT1_2A")
		)
		(pad "2" smd rect
			(at -0.2667 0 90)
			(size 0.3048 0.381)
			(layers "B.Cu" "B.Mask" "B.Paste")
			(net "GND")
		)
	)
	(footprint ""
		(layer "B.Cu")
		(at 88.243918 -338.918042 -90)
		(property "Reference" "PC379_1"
			(at 0 0 90)
			(layer "B.SilkS")
			(hide yes)
			(effects
				(font
					(size 1.27 1.27)
				)
				(justify mirror)
			)
		)
		(property "Value" ""
			(at 0 0 90)
			(layer "B.Fab")
			(effects
				(font
					(size 1.27 1.27)
				)
				(justify mirror)
			)
		)
		(duplicate_pad_numbers_are_jumpers no)
		(fp_line
			(start -1.524 0.762)
			(end 1.524 0.762)
			(stroke
				(width 0.1524)
				(type default)
			)
			(layer "B.SilkS")
		)
		(fp_line
			(start 1.524 0.762)
			(end 1.524 -0.762)
			(stroke
				(width 0.1524)
				(type default)
			)
			(layer "B.SilkS")
		)
		(fp_line
			(start -1.524 -0.762)
			(end -1.524 0.762)
			(stroke
				(width 0.1524)
				(type default)
			)
			(layer "B.SilkS")
		)
		(fp_line
			(start 1.524 -0.762)
			(end -1.524 -0.762)
			(stroke
				(width 0.1524)
				(type default)
			)
			(layer "B.SilkS")
		)
		(fp_line
			(start -1.1049 0.724916)
			(end -1.1049 -0.724916)
			(stroke
				(width 0.1)
				(type default)
			)
			(layer "B.Fab")
		)
		(fp_line
			(start 1.1049 0.724916)
			(end -1.1049 0.724916)
			(stroke
				(width 0.1)
				(type default)
			)
			(layer "B.Fab")
		)
		(fp_line
			(start -1.1049 -0.724916)
			(end 1.1049 -0.724916)
			(stroke
				(width 0.1)
				(type default)
			)
			(layer "B.Fab")
		)
		(fp_line
			(start 1.1049 -0.724916)
			(end 1.1049 0.724916)
			(stroke
				(width 0.1)
				(type default)
			)
			(layer "B.Fab")
		)
		(pad "1" smd rect
			(at 0.889 0 270)
			(size 1.016 1.27)
			(layers "B.Cu" "B.Mask" "B.Paste")
			(net "SW_P12V_AUX_PVDDCR_CPU1_P1_FLT")
		)
		(pad "2" smd rect
			(at -0.889 0 270)
			(size 1.016 1.27)
			(layers "B.Cu" "B.Mask" "B.Paste")
			(net "GND")
		)
	)
	(footprint ""
		(layer "B.Cu")
		(at 182.619142 -244.085364)
		(property "Reference" "R508"
			(at 0 0 0)
			(layer "B.SilkS")
			(hide yes)
			(effects
				(font
					(size 1.27 1.27)
				)
				(justify mirror)
			)
		)
		(property "Value" ""
			(at 0 0 0)
			(layer "B.Fab")
			(effects
				(font
					(size 1.27 1.27)
				)
				(justify mirror)
			)
		)
		(duplicate_pad_numbers_are_jumpers no)
		(fp_line
			(start -0.7874 -0.4064)
			(end -0.7874 0.4064)
			(stroke
				(width 0.1524)
				(type default)
			)
			(layer "B.SilkS")
		)
		(fp_line
			(start -0.7874 0.4064)
			(end 0.7874 0.4064)
			(stroke
				(width 0.1524)
				(type default)
			)
			(layer "B.SilkS")
		)
		(fp_line
			(start 0.7874 -0.4064)
			(end -0.7874 -0.4064)
			(stroke
				(width 0.1524)
				(type default)
			)
			(layer "B.SilkS")
		)
		(fp_line
			(start 0.7874 0.4064)
			(end 0.7874 -0.4064)
			(stroke
				(width 0.1524)
				(type default)
			)
			(layer "B.SilkS")
		)
		(fp_line
			(start -0.67945 -0.3048)
			(end -0.67945 0.3048)
			(stroke
				(width 0.1)
				(type default)
			)
			(layer "B.Fab")
		)
		(fp_line
			(start -0.67945 0.3048)
			(end -0.120396 0.3048)
			(stroke
				(width 0.1)
				(type default)
			)
			(layer "B.Fab")
		)
		(fp_line
			(start -0.12065 -0.3048)
			(end -0.67945 -0.3048)
			(stroke
				(width 0.1)
				(type default)
			)
			(layer "B.Fab")
		)
		(fp_line
			(start -0.12065 -0.2794)
			(end -0.12065 -0.3048)
			(stroke
				(width 0.1)
				(type default)
			)
			(layer "B.Fab")
		)
		(fp_line
			(start -0.120396 0.2794)
			(end 0.12065 0.2794)
			(stroke
				(width 0.1)
				(type default)
			)
			(layer "B.Fab")
		)
		(fp_line
			(start -0.120396 0.3048)
			(end -0.120396 0.2794)
			(stroke
				(width 0.1)
				(type default)
			)
			(layer "B.Fab")
		)
		(fp_line
			(start 0.12065 -0.305054)
			(end 0.12065 -0.2794)
			(stroke
				(width 0.1)
				(type default)
			)
			(layer "B.Fab")
		)
		(fp_line
			(start 0.12065 -0.2794)
			(end -0.12065 -0.2794)
			(stroke
				(width 0.1)
				(type default)
			)
			(layer "B.Fab")
		)
		(fp_line
			(start 0.12065 0.2794)
			(end 0.12065 0.3048)
			(stroke
				(width 0.1)
				(type default)
			)
			(layer "B.Fab")
		)
		(fp_line
			(start 0.12065 0.3048)
			(end 0.67945 0.3048)
			(stroke
				(width 0.1)
				(type default)
			)
			(layer "B.Fab")
		)
		(fp_line
			(start 0.67945 -0.305054)
			(end 0.12065 -0.305054)
			(stroke
				(width 0.1)
				(type default)
			)
			(layer "B.Fab")
		)
		(fp_line
			(start 0.67945 0.3048)
			(end 0.67945 -0.305054)
			(stroke
				(width 0.1)
				(type default)
			)
			(layer "B.Fab")
		)
		(pad "1" smd circle
			(at 0.40005 0 180)
			(size 0 0)
			(layers "B.Cu" "B.Mask" "B.Paste")
			(net "M_I_CPU1_ALERT_N")
		)
		(pad "2" smd circle
			(at -0.40005 0 180)
			(size 0 0)
			(layers "B.Cu" "B.Mask" "B.Paste")
			(net "M_I_CPU1_ALERT_R_N")
		)
	)
	(footprint ""
		(layer "B.Cu")
		(at 237.871 -227.203)
		(property "Reference" "R789"
			(at 0 0 0)
			(layer "B.SilkS")
			(hide yes)
			(effects
				(font
					(size 1.27 1.27)
				)
				(justify mirror)
			)
		)
		(property "Value" ""
			(at 0 0 0)
			(layer "B.Fab")
			(effects
				(font
					(size 1.27 1.27)
				)
				(justify mirror)
			)
		)
		(duplicate_pad_numbers_are_jumpers no)
		(fp_line
			(start -0.7874 -0.4064)
			(end -0.7874 0.4064)
			(stroke
				(width 0.1524)
				(type default)
			)
			(layer "B.SilkS")
		)
		(fp_line
			(start -0.7874 0.4064)
			(end 0.7874 0.4064)
			(stroke
				(width 0.1524)
				(type default)
			)
			(layer "B.SilkS")
		)
		(fp_line
			(start 0.7874 -0.4064)
			(end -0.7874 -0.4064)
			(stroke
				(width 0.1524)
				(type default)
			)
			(layer "B.SilkS")
		)
		(fp_line
			(start 0.7874 0.4064)
			(end 0.7874 -0.4064)
			(stroke
				(width 0.1524)
				(type default)
			)
			(layer "B.SilkS")
		)
		(fp_line
			(start -0.67945 -0.3048)
			(end -0.67945 0.3048)
			(stroke
				(width 0.1)
				(type default)
			)
			(layer "B.Fab")
		)
		(fp_line
			(start -0.67945 0.3048)
			(end -0.120396 0.3048)
			(stroke
				(width 0.1)
				(type default)
			)
			(layer "B.Fab")
		)
		(fp_line
			(start -0.12065 -0.3048)
			(end -0.67945 -0.3048)
			(stroke
				(width 0.1)
				(type default)
			)
			(layer "B.Fab")
		)
		(fp_line
			(start -0.12065 -0.2794)
			(end -0.12065 -0.3048)
			(stroke
				(width 0.1)
				(type default)
			)
			(layer "B.Fab")
		)
		(fp_line
			(start -0.120396 0.2794)
			(end 0.12065 0.2794)
			(stroke
				(width 0.1)
				(type default)
			)
			(layer "B.Fab")
		)
		(fp_line
			(start -0.120396 0.3048)
			(end -0.120396 0.2794)
			(stroke
				(width 0.1)
				(type default)
			)
			(layer "B.Fab")
		)
		(fp_line
			(start 0.12065 -0.305054)
			(end 0.12065 -0.2794)
			(stroke
				(width 0.1)
				(type default)
			)
			(layer "B.Fab")
		)
		(fp_line
			(start 0.12065 -0.2794)
			(end -0.12065 -0.2794)
			(stroke
				(width 0.1)
				(type default)
			)
			(layer "B.Fab")
		)
		(fp_line
			(start 0.12065 0.2794)
			(end 0.12065 0.3048)
			(stroke
				(width 0.1)
				(type default)
			)
			(layer "B.Fab")
		)
		(fp_line
			(start 0.12065 0.3048)
			(end 0.67945 0.3048)
			(stroke
				(width 0.1)
				(type default)
			)
			(layer "B.Fab")
		)
		(fp_line
			(start 0.67945 -0.305054)
			(end 0.12065 -0.305054)
			(stroke
				(width 0.1)
				(type default)
			)
			(layer "B.Fab")
		)
		(fp_line
			(start 0.67945 0.3048)
			(end 0.67945 -0.305054)
			(stroke
				(width 0.1)
				(type default)
			)
			(layer "B.Fab")
		)
		(pad "1" smd circle
			(at 0.40005 0 180)
			(size 0 0)
			(layers "B.Cu" "B.Mask" "B.Paste")
			(net "SMB_CPU0_CPU1_APML_BUF1_SCL")
		)
		(pad "2" smd circle
			(at -0.40005 0 180)
			(size 0 0)
			(layers "B.Cu" "B.Mask" "B.Paste")
			(net "SMB_CPU0_CPU1_APML_BUF1_SCL_R1")
		)
	)
)
